1
1
2
2
3
3
4
4
5
5
6
6
D D
C C
B B
A A
timingcard.com
1SHEET OF 7
Cannot open file 
C:\Users\<user>\Desktop\Ti
mecard 
Logo\TIMECARD.jpg
+3.3V+3.3V+3.3V+3.3V
LED1 LED2 LED3 LED4
RED
D14
RED
D13
RED
D12
RED
D11
LEDS
GND
GND
GND
GND
ANT1
ANT2
ANT4
ANT3
TIMECARD OUTPUT
R16
200 OHM
R28
200 OHM
R29
200 OHM
R30
200 OHM
1
2
3
J6
1909763-15
1
2
3
4
AN1
901-143-6RFX
1
2
3
J5
1909763-15
1
2
3
4
AN2
901-143-6RFX
1
2
3
J10
1909763-15
1
2
3
4
AN4
901-143-6RFX
1
2
3
J9
1909763-15
1
2
3
4
AN3
901-143-6RFX
GND GND
GND
GND
1
2
GND 3
4
VCC5
U6
NC7SZ125M5
R14
49.9R
GNDGND
C26
0.1uF
GND
+3.3V
1
2
GND 3
4
VCC5
U11
NC7SZ125M5
R17
49.9R
GNDGND
C28
0.1uF
GND
+3.3V
1
2
GND3
4
VCC 5
U8
NC7SZ125M5
R15
49.9R
GNDGND
C27
0.1uF
GND
+3.3V
1
2
GND3
4
VCC 5
U12
NC7SZ125M5
R25
49.9R
GNDGND
C29
0.1uF
+3.3V
GND
TIMECARD INPUT
1
2 3
4
D2
8240136
+3.3V
GND
1
2 3
4
D1
8240136
+3.3V
GND
PIAN101 
PIAN102 PIAN103 PIAN104 PIAN105 
COAN1 
PIAN201 
PIAN202 PIAN203 PIAN204 PIAN205 
COAN2 
PIAN301 
PIAN302 PIAN303 PIAN304 PIAN305 
COAN3 
PIAN401 
PIAN402 PIAN403 PIAN404 PIAN405 
COAN4 
PIC2601 
PIC2602 COC26 
PIC2701 
PIC2702 COC27 
PIC2801 
PIC2802 COC28 
PIC2901 
PIC2902 COC29 
PID101 PID102 
PID103 PID104 COD1 
PID201 PID202 
PID203 PID204 COD2 
PID1101 
PID1102 
COD11 
PID1201 
PID1202 
COD12 
PID1301 
PID1302 
COD13 
PID1401 
PID1402 
COD14 
PIJ501 
PIJ502 
PIJ503 
COJ5 
PIJ601 
PIJ602 
PIJ603 
COJ6 
PIJ901 
PIJ902 
PIJ903 
COJ9 
PIJ1001 
PIJ1002 
PIJ1003 
COJ10 
PIR1401 PIR1402 
COR14 
PIR1501 PIR1502 
COR15 
PIR1601 
PIR1602 COR16 
PIR1701 PIR1702 
COR17 
PIR2501 PIR2502 
COR25 
PIR2801 
PIR2802 COR28 
PIR2901 
PIR2902 COR29 
PIR3001 
PIR3002 COR30 
PIU601 
PIU602 
PIU603 
PIU604 
PIU605 
COU6 
PIU801 
PIU802 
PIU803 
PIU804 
PIU805 
COU8 
PIU1101 
PIU1102 
PIU1103 
PIU1104 
PIU1105 
COU11 PIU1201 
PIU1202 
PIU1203 
PIU1204 
PIU1205 
COU12 



1
1
2
2
3
3
4
4
5
5
6
6
D D
C C
B B
A A
timingcard.com
2SHEET OF 7
Cannot open file 
C:\Users\<user>\Desktop\Ti
mecard 
Logo\TIMECARD.jpg
+12V
GND
+5.0V
+3.3V
GND GND
GNDGND GND
+3.3V
+12V
+12V
39V
DFLZ39
D3
10uF
C1
10uF
C6
10uF
C14
10uF
C13
10uF
C5
10uF
C7
10uF
C8
RED
D4
200 OHM
R1
47K
R2
2.2K
R8
10K
R6
47K
R4
0.01uF
C4
10.uH
L1
10.uH
L2
0.01uF
C3
47K
R3
10K
R7
2.2K
R9
26.1K
R5
MP1482DS
BS 1
IN 2
SW 3
FB 5
EN7
SS8
GND4
COMP6
U1
MP1482DS
BS 1
IN 2
SW 3
FB 5
EN7
SS8
GND4
COMP6
U2
+12V_PCIE
2.00A
F1
C20.1uF
C15
0.1uF
C16
0.1uF
C17
0.1uF
C18
0.1uFC190.1uF
C210.1uF
C9
0.1uF
C100.1uF C110.1uF C120.1uF
C22
0.033uF
C20
0.033uF
PIC101 
PIC102 
COC1 
PIC201 
PIC202 COC2 
PIC301 PIC302 
COC3 
PIC401 PIC402 
COC4 
PIC501 
PIC502 
COC5 
PIC601 
PIC602 
COC6 
PIC701 
PIC702 
COC7 PIC801 
PIC802 
COC8 
PIC901 
PIC902 COC9 
PIC1001 
PIC1002 COC10 
PIC1101 
PIC1102 COC11 
PIC1201 
PIC1202 COC12 
PIC1301 
PIC1302 
COC13 PIC1401 
PIC1402 
COC14 
PIC1501 
PIC1502 COC15 
PIC1601 
PIC1602 COC16 
PIC1701 
PIC1702 COC17 
PIC1801 
PIC1802 COC18 
PIC1901 
PIC1902 COC19 
PIC2001 
PIC2002 
COC20 
PIC2101 
PIC2102 COC21 
PIC2201 
PIC2202 
COC22 
PID301 PID302 
COD3 
PID401 
PID402 
COD4 
PIF101 PIF102 
COF1 
PIL101 PIL102 
COL1 
PIL201 PIL202 
COL2 
PIR101 
PIR102 
COR1 
PIR201 
PIR202 COR2 
PIR301 
PIR302 COR3 
PIR401 PIR402 
COR4 
PIR501 PIR502 
COR5 
PIR601 
PIR602 
COR6 
PIR701 
PIR702 
COR7 
PIR801 PIR802 
COR8 
PIR901 PIR902 
COR9 
PIU101 PIU102 
PIU103 
PIU104 
PIU105 
PIU106 
PIU107 
PIU108 
COU1 
PIU201 PIU202 
PIU203 
PIU204 
PIU205 
PIU206 
PIU207 
PIU208 
COU2 



1
1
2
2
3
3
4
4
5
5
6
6
D D
C C
B B
A A
timingcard.com
3SHEET OF 7
Cannot open file 
C:\Users\<user>\Desktop\Ti
mecard 
Logo\TIMECARD.jpg
GND GND
+12V_PCIE+3.3V_PCIE
+3.3V
+3.3V_PCIE
+12V_PCIE
PCIE_RX0_P
PCIE_RX0_N
PCIE_RX1_P
PCIE_RX1_N
PCIE_RX2_P
PCIE_RX2_N
PCIE_RX3_P
PCIE_RX3_N
PCIE_PERST
PCIE_CLK_P
PCIE_CLK_N
PCIE_TX0_P
PCIE_TX0_N
PCIE_TX1_P
PCIE_TX1_N
PCIE_TX2_P
PCIE_TX2_N
PCIE_TX3_P
PCIE_TX3_N
PCIe Connector
4.7K
R22
0.1UFC53
0.1UFC52
0 OHM
R24
0 OHM
R23
0.1UFC51
0.1UFC49
0.1UFC47
0.1UFC45
0.1UFC44
0.1UFC46
0.1UFC48
0.1UFC50
KEY KEY
+12v1B1
+12V2B2
+12V3B3
GND1B4
SMCLKB5
SMDATAB6
GND2B7
+3.3V1B8
JTAG/TRST_nB9
+3.3vauxB10
WAKE_nB11
RESERVED1B12
GND3B13
PETp0B14
PETn0B15
GND4B16
PRSNT2_nB17
GND5B18
PETp1B19
PETn1B20
GND6B21
GND7B22
PETp2B23
PETn2B24
GND8B25
GND9B26
PETp3B27
PETn3B28
GND10B29
RESERVED2B30
PRSNT4_nB31
GND11B32
PRSNT1_n A1
+12V5 A2
+12V4 A3
GND37 A4
JTAG/TCK A5
JTAG/TDI A6
JTAG/TDO A7
JTAG/TMS A8
+3.3V3 A9
+3.3V2 A10
PERST A11
GND36 A12
REFCLK+ A13
REFCLK- A14
GND35 A15
PERp0 A16
PERn0 A17
GND34 A18
RESERVED5 A19
GND33 A20
PERp1 A21
PERn1 A22
GND32 A23
GND31 A24
PERp2 A25
PERn2 A26
GND30 A27
GND29 A28
PERp3 A29
PERn3 A30
GND28 A31
RESERVED4 A32
P2
PCIex4
GND
+3.3V
GND GND GND GND+3.3V +3.3V +3.3V +3.3V
FPGA_TCK
FPGA_TDO
FPGA_TMS
FPGA_TDI
JTAG
33 OHM
R18
33 OHM
R19
33 OHM
R20
33 OHM
R21
2X5
9
3
10
4
1
5
7
2
6
8
U5
BAT54SW
2
3
1
D8
BAT54SW
2
3
1
D7
BAT54SW
2
3
1
D6
BAT54SW
2
3
1
D5
PRSNT
PRSNT
PRSNT
FPGA_TCK FPGA_TDO FPGA_TMS FPGA_TDI
PIC4401 PIC4402 COC44 
PIC4501 PIC4502 
COC45 
PIC4601 PIC4602 COC46 
PIC4701 PIC4702 
COC47 
PIC4801 PIC4802 COC48 
PIC4901 PIC4902 
COC49 
PIC5001 PIC5002 COC50 
PIC5101 PIC5102 
COC51 
PIC5201 PIC5202 
COC52 
PIC5301 PIC5302 
COC53 
PID501 PID502 
PID503 
COD5 
PID601 PID602 
PID603 
COD6 
PID701 PID702 
PID703 
COD7 
PID801 PID802 
PID803 
COD8 
PIP20A1 
PIP20A2 
PIP20A3 
PIP20A4 
PIP20A5 
PIP20A6 
PIP20A7 
PIP20A8 
PIP20A9 
PIP20A10 
PIP20A11 
PIP20A12 
PIP20A13 
PIP20A14 
PIP20A15 
PIP20A16 
PIP20A17 
PIP20A18 
PIP20A19 
PIP20A20 
PIP20A21 
PIP20A22 
PIP20A23 
PIP20A24 
PIP20A25 
PIP20A26 
PIP20A27 
PIP20A28 
PIP20A29 
PIP20A30 
PIP20A31 
PIP20A32 
PIP20B1 
PIP20B2 
PIP20B3 
PIP20B4 
PIP20B5 
PIP20B6 
PIP20B7 
PIP20B8 
PIP20B9 
PIP20B10 
PIP20B11 
PIP20B12 
PIP20B13 
PIP20B14 
PIP20B15 
PIP20B16 
PIP20B17 
PIP20B18 
PIP20B19 
PIP20B20 
PIP20B21 
PIP20B22 
PIP20B23 
PIP20B24 
PIP20B25 
PIP20B26 
PIP20B27 
PIP20B28 
PIP20B29 
PIP20B30 
PIP20B31 
PIP20B32 
COP2 
PIR1801 PIR1802 
COR18 
PIR1901 PIR1902 
COR19 
PIR2001 PIR2002 
COR20 
PIR2101 PIR2102 
COR21 
PIR2201 
PIR2202 
COR22 
PIR2301 PIR2302 
COR23 
PIR2401 PIR2402 
COR24 
PIU501 PIU502 
PIU503 PIU504 
PIU505 PIU506 
PIU507 PIU508 
PIU509 PIU5010 
COU5 



1
1
2
2
3
3
4
4
5
5
6
6
D D
C C
B B
A A
timingcard.com
5SHEET OF 7
Cannot open file 
C:\Users\<user>\Desktop\Ti
mecard 
Logo\TIMECARD.jpg
+5.0V
GND
+3.3V
GND GND
GPS1_TP2
GPS1_TP1
GPS1_RX
GPS1_TX
GPS1_RST
GPS
10uF
C58
10uF
C60
VCC_ANT1
VCC2
TXD3
RST4 RXD 5TP1 6TP2 7GND 8
U9
RCB-F9T
VCC4 SCL 1
SDA 3
WP5 GND 2
U7
AT24MAC402-STUM-T
SDA
SCL
+3.3V
GND
C590.1uF C610.1uF C250.1uF
+3.3V
GND
EXT_EEPROM_WP
R37
10K
EEPROM
VDD8
VDDIO6
CS 2
SCK 4
SDI 3
SDO 5
GND 1
GND 7
U14
BME280
VDD8
VDDIO5 INT1 4
INT2 9
CS12
SCX13
SDO 1
SDX 14
NC10 NC11 GND 2
GND 3
GND 7
GNDIO 6
U13
BMX160
C330.1uFC320.1uF
GNDGND GND
SDA
SCL
+3.3V +3.3V +3.3V
GNDGNDGND
C310.1uFC300.1uF
+3.3V+3.3V
SCL
SDA
+3.3V
GND GND
ENVIRONMENT (0x76) IMU (0x68)
SCLSDA
+3.3V+3.3V
R27
4.7K
R26
4.7K
1
2
3
4
P3
AUX Sensor
+3.3V
GND
SDA
SCL
PIC2501 
PIC2502 COC25 
PIC3001 
PIC3002 COC30 
PIC3101 
PIC3102 COC31 
PIC3201 
PIC3202 COC32 
PIC3301 
PIC3302 COC33 
PIC5801 
PIC5802 
COC58 
PIC5901 
PIC5902 COC59 PIC6001 
PIC6002 
COC60 
PIC6101 
PIC6102 COC61 
PIP301 
PIP302 
PIP303 
PIP304 
COP3 
PIR2601 
PIR2602 
COR26 
PIR2701 
PIR2702 
COR27 
PIR3701 
PIR3702 
COR37 
PIU701 
PIU702 
PIU703 
PIU704 
PIU705 
COU7 
PIU901 
PIU902 
PIU903 
PIU904 PIU905 
PIU906 
PIU907 
PIU908 
COU9 
PIU1301 
PIU1302 
PIU1303 
PIU1304 
PIU1305 
PIU1306 
PIU1307 
PIU1308 
PIU1309 
PIU13010 
PIU13011 
PIU13012 
PIU13013 
PIU13014 
COU13 
PIU1401 
PIU1402 
PIU1403 
PIU1404 
PIU1405 
PIU1406 
PIU1407 
PIU1408 
COU14 



1
1
2
2
3
3
4
4
5
5
6
6
D D
C C
B B
A A
timingcard.com
6SHEET OF 7
Cannot open file 
C:\Users\<user>\Desktop\Ti
mecard 
Logo\TIMECARD.jpg
MAC_TX
MAC_RX
MAC_BITEMAC_RF_OUT
MAC_FREQ_CTRL
FPGA_MAC_PPS_IN0-
MAC_USB+
MAC_USB-
MAC_USB_PWR
MAC_PPS_OUT+
MAC_PPS_OUT-
MAC_ALARM
GND
GND
+5.0V
GND
MAC
10uF
C62
FREQ CTRL INP1
GND (CASE)P2
RF OUTP3
GND (SUPPLY & SIGNAL)P4 VCC P5BITE P6RS-232 TX P7RS-232 RX P8
RV-3049-C3
U10A
RV-3049-C3
PPS-IN 1+1 USB DATA + 2
PPS-IN 1-3 USB DATA - 4
PPS-IN 0+5 USB POWER 6
PPS-IN 0-7
GND 8
GND 9
NC10
NC11
NC12
NC13
NC14
GND 15NC16
PPS-OUT + 17
NC18
PPS-OUT - 19
ALARM 20
U10B
C630.1uF
DI12
DI23
DO+1 7
DO+2 6
DO-1 8
DO-2 5
GND 4VCC1
U3
DS90LV027AQMA
RIN1-1 RIN1+2
RIN2+3
RIN2-4
GND 5
ROUT2 6
ROUT1 7
VCC8
U4
DS90LV028AQMA
R11
4.7K
R10
4.7K C230.1uF
GNDGNDGND
+3.3V
MAC_PPS_IN1-
MAC_PPS_IN1+
MAC_PPS_IN0-
MAC_PPS_IN0+
GND
MAC_PPS_IN1-
MAC_PPS_IN1+
MAC_PPS_IN0-
MAC_PPS_IN0+
R12
110R
C24
0.1uF
+3.3V
GND GND
R13
49.9R
FPGA_MAC_PPS_OUT-
MAC_PPS_OUT+
MAC_PPS_OUT-
FPGA_MAC_PPS_IN1-
PIC2301 
PIC2302 COC23 
PIC2401 
PIC2402 COC24 
PIC6201 
PIC6202 
COC62 
PIC6301 
PIC6302 COC63 
PIR1001 
PIR1002 COR10 
PIR1101 
PIR1102 COR11 
PIR1201 
PIR1202 
COR12 
PIR1301 PIR1302 
COR13 
PIU301 
PIU302 
PIU303 
PIU304 
PIU305 
PIU306 
PIU307 
PIU308 
COU3 
PIU401 
PIU402 
PIU403 
PIU404 
PIU405 
PIU406 
PIU407 
PIU408 
COU4 
PIU100P1 
PIU100P2 
PIU100P3 
PIU100P4 PIU100P5 
PIU100P6 
PIU100P7 
PIU100P8 
COU10A 
PIU1001 PIU1002 
PIU1003 PIU1004 
PIU1005 PIU1006 
PIU1007 
PIU1008 
PIU1009 
PIU10010 
PIU10011 
PIU10012 
PIU10013 
PIU10014 
PIU10015 
PIU10016 
PIU10017 
PIU10018 
PIU10019 
PIU10020 
COU10B 



1
1
2
2
3
3
4
4
5
5
6
6
D D
C C
B B
A A
timingcard.com
7SHEET OF 7
Cannot open file 
C:\Users\<user>\Desktop\Ti
mecard 
Logo\TIMECARD.jpg
+5.0V
GND
KEY2
LED4
LED3
LED2
LED1
+5.0V
GND
GPS1_RST
GPS1_TP1
GPS1_TP2
GND
GPS1_RX
MAC_ALARM
MAC_BITE
MAC_FREQ_CTRL
FPGA_MAC_PPS_IN0-
FPGA_MAC_PPS_IN1-
FPGA_MAC_PPS_OUT-
MAC_RF_OUT
ANT1
ANT2
ANT3
ANT4
SDA
SCL
GND
GPS1_TX
MAC_RX
MAC_TX
MAC_USB+
MAC_USB-
MAC_USB_PWR
GND
PCIE_PERST
KEY1
FPGA_TCK
FPGA_TDO
GND
FPGA_TDI
FPGA_TMS
GND
PCIE_TX3_P
PCIE_TX3_N
PCIE_RX3_P
PCIE_RX3_N
PCIE_TX0_P
PCIE_TX0_N
PCIE_RX0_P
PCIE_RX0_N
GND
PCIE_TX2_P
PCIE_TX2_N
PCIE_RX2_P
PCIE_RX2_N
PCIE_TX1_P
PCIE_TX1_N
PCIE_RX1_P
PCIE_RX1_N
PCIE_CLK_P
PCIE_CLK_N
1A-1 2 A-2
3A-3 4 A-4
5A-5 6 A-6
7A-7 8 A-8
9A-9 10 A-10
11A-11 12 A-12
13A-13 14 A-14
15A-15 16 A-16
17A-17 18 A-18
19A-19 20 A-20
21A-21 22 A-22
23A-23 24 A-24
25A-25 26 A-26
27A-27 28 A-28
29A-29 30 A-30
31A-31 32 A-32
33A-33 34 A-34
35A-35 36 A-36
37A-37 38 A-38
39A-39 40 A-40
41A-41 42 A-42
43A-43 44 A-44
45A-45 46 A-46
47A-47 48 A-48
49A-49 50 A-50
51A-51 52 A-52
53A-53 54 A-54
55A-55 56 A-56
57A-57 58 A-58
59A-59 60 A-60
61A-61 62 A-62
63A-63 64 A-64
65A-65 66 A-66
67A-67 68 A-68
69A-69 70 A-70
71A-71 72 A-72
73A-73 74 A-74
75A-75 76 A-76
77A-77 78 A-78
79A-79 80 A-80
81A-81 82 A-82
83A-83 84 A-84
P1A
FPGA_CONN
1B-1 2 B-2
3B-3 4 B-4
5B-5 6 B-6
7B-7 8 B-8
9B-9 10 B-10
11B-11 12 B-12
13B-13 14 B-14
15B-15 16 B-16
17B-17 18 B-18
19B-19 20 B-20
21B-21 22 B-22
23B-23 24 B-24
25B-25 26 B-26
27B-27 28 B-28
29B-29 30 B-30
31B-31 32 B-32
33B-33 34 B-34
35B-35 36 B-36
37B-37 38 B-38
39B-39 40 B-40
41B-41 42 B-42
43B-43 44 B-44
45B-45 46 B-46
47B-47 48 B-48
49B-49 50 B-50
51B-51 52 B-52
53B-53 54 B-54
55B-55 56 B-56
57B-57 58 B-58
59B-59 60 B-60
61B-61 62 B-62
63B-63 64 B-64
65B-65 66 B-66
67B-67 68 B-68
69B-69 70 B-70
71B-71 72 B-72
73B-73 74 B-74
75B-75 76 B-76
77B-77 78 B-78
79B-79 80 B-80
81B-81 82 B-82
83B-83 84 B-84
P1B
FPGA_CONN
1C-1 2 C-2
3C-3 4 C-4
5C-5 6 C-6
7C-7 8 C-8
9C-9 10 C-10
11C-11 12 C-12
13C-13 14 C-14
15C-15 16 C-16
17C-17 18 C-18
19C-19 20 C-20
21C-21 22 C-22
23C-23 24 C-24
25C-25 26 C-26
27C-27 28 C-28
29C-29 30 C-30
31C-31 32 C-32
33C-33 34 C-34
35C-35 36 C-36
37C-37 38 C-38
39C-39 40 C-40
41C-41 42 C-42
43C-43 44 C-44
45C-45 46 C-46
47C-47 48 C-48
49C-49 50 C-50
51C-51 52 C-52
53C-53 54 C-54
55C-55 56 C-56
57C-57 58 C-58
59C-59 60 C-60
61C-61 62 C-62
63C-63 64 C-64
65C-65 66 C-66
67C-67 68 C-68
69C-69 70 C-70
71C-71 72 C-72
73C-73 74 C-74
75C-75 76 C-76
77C-77 78 C-78
79C-79 80 C-80
81C-81 82 C-82
83C-83 84 C-84
P1C
FPGA_CONN
1D-1 2 D-2
3D-3 4 D-4
5D-5 6 D-6
7D-7 8 D-8
9D-9 10 D-10
11D-11 12 D-12
13D-13 14 D-14
15D-15 16 D-16
17D-17 18 D-18
19D-19 20 D-20
21D-21 22 D-22
23D-23 24 D-24
25D-25 26 D-26
27D-27 28 D-28
29D-29 30 D-30
31D-31 32 D-32
33D-33 34 D-34
35D-35 36 D-36
37D-37 38 D-38
39D-39 40 D-40
41D-41 42 D-42
43D-43 44 D-44
45D-45 46 D-46
47D-47 48 D-48
49D-49 50 D-50
51D-51 52 D-52
53D-53 54 D-54
55D-55 56 D-56
57D-57 58 D-58
59D-59 60 D-60
61D-61 62 D-62
63D-63 64 D-64
65D-65 66 D-66
67D-67 68 D-68
69D-69 70 D-70
71D-71 72 D-72
73D-73 74 D-74
75D-75 76 D-76
77D-77 78 D-78
79D-79 80 D-80
81D-81 82 D-82
83D-83 84 D-84
P1D
FPGA_CONN
EXT_EEPROM_WP
PIP10A01 PIP10A02 
PIP10A03 PIP10A04 
PIP10A05 PIP10A06 
PIP10A07 PIP10A08 
PIP10A09 PIP10A010 
PIP10A011 PIP10A012 
PIP10A013 PIP10A014 
PIP10A015 PIP10A016 
PIP10A017 PIP10A018 
PIP10A019 PIP10A020 
PIP10A021 PIP10A022 
PIP10A023 PIP10A024 
PIP10A025 PIP10A026 
PIP10A027 PIP10A028 
PIP10A029 PIP10A030 
PIP10A031 PIP10A032 
PIP10A033 PIP10A034 
PIP10A035 PIP10A036 
PIP10A037 PIP10A038 
PIP10A039 PIP10A040 
PIP10A041 PIP10A042 
PIP10A043 PIP10A044 
PIP10A045 PIP10A046 
PIP10A047 PIP10A048 
PIP10A049 PIP10A050 
PIP10A051 PIP10A052 
PIP10A053 PIP10A054 
PIP10A055 PIP10A056 
PIP10A057 PIP10A058 
PIP10A059 PIP10A060 
PIP10A061 PIP10A062 
PIP10A063 PIP10A064 
PIP10A065 PIP10A066 
PIP10A067 PIP10A068 
PIP10A069 PIP10A070 
PIP10A071 PIP10A072 
PIP10A073 PIP10A074 
PIP10A075 PIP10A076 
PIP10A077 PIP10A078 
PIP10A079 PIP10A080 
PIP10A081 PIP10A082 
PIP10A083 PIP10A084 
COP1A 
PIP10B01 PIP10B02 
PIP10B03 PIP10B04 
PIP10B05 PIP10B06 
PIP10B07 PIP10B08 
PIP10B09 PIP10B010 
PIP10B011 PIP10B012 
PIP10B013 PIP10B014 
PIP10B015 PIP10B016 
PIP10B017 PIP10B018 
PIP10B019 PIP10B020 
PIP10B021 PIP10B022 
PIP10B023 PIP10B024 
PIP10B025 PIP10B026 
PIP10B027 PIP10B028 
PIP10B029 PIP10B030 
PIP10B031 PIP10B032 
PIP10B033 PIP10B034 
PIP10B035 PIP10B036 
PIP10B037 PIP10B038 
PIP10B039 PIP10B040 
PIP10B041 PIP10B042 
PIP10B043 PIP10B044 
PIP10B045 PIP10B046 
PIP10B047 PIP10B048 
PIP10B049 PIP10B050 
PIP10B051 PIP10B052 
PIP10B053 PIP10B054 
PIP10B055 PIP10B056 
PIP10B057 PIP10B058 
PIP10B059 PIP10B060 
PIP10B061 PIP10B062 
PIP10B063 PIP10B064 
PIP10B065 PIP10B066 
PIP10B067 PIP10B068 
PIP10B069 PIP10B070 
PIP10B071 PIP10B072 
PIP10B073 PIP10B074 
PIP10B075 PIP10B076 
PIP10B077 PIP10B078 
PIP10B079 PIP10B080 
PIP10B081 PIP10B082 
PIP10B083 PIP10B084 
COP1B 
PIP10C01 PIP10C02 
PIP10C03 PIP10C04 
PIP10C05 PIP10C06 
PIP10C07 PIP10C08 
PIP10C09 PIP10C010 
PIP10C011 PIP10C012 
PIP10C013 PIP10C014 
PIP10C015 PIP10C016 
PIP10C017 PIP10C018 
PIP10C019 PIP10C020 
PIP10C021 PIP10C022 
PIP10C023 PIP10C024 
PIP10C025 PIP10C026 
PIP10C027 PIP10C028 
PIP10C029 PIP10C030 
PIP10C031 PIP10C032 
PIP10C033 PIP10C034 
PIP10C035 PIP10C036 
PIP10C037 PIP10C038 
PIP10C039 PIP10C040 
PIP10C041 PIP10C042 
PIP10C043 PIP10C044 
PIP10C045 PIP10C046 
PIP10C047 PIP10C048 
PIP10C049 PIP10C050 
PIP10C051 PIP10C052 
PIP10C053 PIP10C054 
PIP10C055 PIP10C056 
PIP10C057 PIP10C058 
PIP10C059 PIP10C060 
PIP10C061 PIP10C062 
PIP10C063 PIP10C064 
PIP10C065 PIP10C066 
PIP10C067 PIP10C068 
PIP10C069 PIP10C070 
PIP10C071 PIP10C072 
PIP10C073 PIP10C074 
PIP10C075 PIP10C076 
PIP10C077 PIP10C078 
PIP10C079 PIP10C080 
PIP10C081 PIP10C082 
PIP10C083 PIP10C084 
COP1C 
PIP10D01 PIP10D02 
PIP10D03 PIP10D04 
PIP10D05 PIP10D06 
PIP10D07 PIP10D08 
PIP10D09 PIP10D010 
PIP10D011 PIP10D012 
PIP10D013 PIP10D014 
PIP10D015 PIP10D016 
PIP10D017 PIP10D018 
PIP10D019 PIP10D020 
PIP10D021 PIP10D022 
PIP10D023 PIP10D024 
PIP10D025 PIP10D026 
PIP10D027 PIP10D028 
PIP10D029 PIP10D030 
PIP10D031 PIP10D032 
PIP10D033 PIP10D034 
PIP10D035 PIP10D036 
PIP10D037 PIP10D038 
PIP10D039 PIP10D040 
PIP10D041 PIP10D042 
PIP10D043 PIP10D044 
PIP10D045 PIP10D046 
PIP10D047 PIP10D048 
PIP10D049 PIP10D050 
PIP10D051 PIP10D052 
PIP10D053 PIP10D054 
PIP10D055 PIP10D056 
PIP10D057 PIP10D058 
PIP10D059 PIP10D060 
PIP10D061 PIP10D062 
PIP10D063 PIP10D064 
PIP10D065 PIP10D066 
PIP10D067 PIP10D068 
PIP10D069 PIP10D070 
PIP10D071 PIP10D072 
PIP10D073 PIP10D074 
PIP10D075 PIP10D076 
PIP10D077 PIP10D078 
PIP10D079 PIP10D080 
PIP10D081 PIP10D082 
PIP10D083 PIP10D084 
COP1D 